(kicad_pcb
	(version 20260206)
	(generator "pcbnew")
	(generator_version "10.0")
	(general
		(thickness 1.6)
		(legacy_teardrops no)
	)
	(paper "A4")
	(title_block
		(title "01162023_DA0F0TEBIF0_F0T_Expander_BD_F_brd_V02_OCP.brd")
		(comment 1 "Grand Teton / footprints 5199-5204 of 9728")
	)
	(layers
		(0 "F.Cu" signal "TOP")
		(4 "In1.Cu" signal "GND")
		(6 "In2.Cu" signal "VCC")
		(8 "In3.Cu" signal "VCC1")
		(10 "In4.Cu" signal "GND1")
		(12 "In5.Cu" signal "IN1")
		(14 "In6.Cu" signal "GND2")
		(16 "In7.Cu" signal "IN2")
		(18 "In8.Cu" signal "GND3")
		(20 "In9.Cu" signal "IN3")
		(22 "In10.Cu" signal "GND4")
		(24 "In11.Cu" signal "IN4")
		(26 "In12.Cu" signal "GND5")
		(28 "In13.Cu" signal "IN5")
		(30 "In14.Cu" signal "GND6")
		(32 "In15.Cu" signal "IN6")
		(34 "In16.Cu" signal "GND7")
		(2 "B.Cu" signal "BOTTOM")
		(9 "F.Adhes" user "F.Adhesive")
		(11 "B.Adhes" user "B.Adhesive")
		(13 "F.Paste" user "Package Geometry/Pastemask Top")
		(15 "B.Paste" user "Package Geometry/Pastemask Bottom")
		(5 "F.SilkS" user "Ref Des/Silkscreen Top")
		(7 "B.SilkS" user "Ref Des/Silkscreen Bottom")
		(1 "F.Mask" user "Board Geometry/Soldermask Top")
		(3 "B.Mask" user "Board Geometry/Soldermask Bottom")
		(17 "Dwgs.User" user "User.Drawings")
		(19 "Cmts.User" user "User.Comments")
		(21 "Eco1.User" user "User.Eco1")
		(23 "Eco2.User" user "User.Eco2")
		(25 "Edge.Cuts" user "Board Geometry/Outline")
		(27 "Margin" user)
		(31 "F.CrtYd" user "Package Geometry/Place Bound Top")
		(29 "B.CrtYd" user "Package Geometry/Place Bound Bottom")
		(35 "F.Fab" user "Ref Des/Assembly Top")
		(33 "B.Fab" user "Ref Des/Assembly Bottom")
	)
	(footprint ""
		(layer "F.Cu")
		(at 58.575702 -36.915598 -90)
		(property "Reference" "R5547"
			(at 0 0 270)
			(layer "F.SilkS")
			(hide yes)
			(effects
				(font
					(size 1.27 1.27)
				)
			)
		)
		(property "Value" ""
			(at 0 0 270)
			(layer "F.Fab")
			(effects
				(font
					(size 1.27 1.27)
				)
			)
		)
		(duplicate_pad_numbers_are_jumpers no)
		(fp_line
			(start -0.7874 0.4064)
			(end -0.7874 -0.4064)
			(stroke
				(width 0.1524)
				(type default)
			)
			(layer "F.SilkS")
		)
		(fp_line
			(start 0.7874 0.4064)
			(end -0.7874 0.4064)
			(stroke
				(width 0.1524)
				(type default)
			)
			(layer "F.SilkS")
		)
		(fp_line
			(start -0.7874 -0.4064)
			(end 0.7874 -0.4064)
			(stroke
				(width 0.1524)
				(type default)
			)
			(layer "F.SilkS")
		)
		(fp_line
			(start 0.7874 -0.4064)
			(end 0.7874 0.4064)
			(stroke
				(width 0.1524)
				(type default)
			)
			(layer "F.SilkS")
		)
		(fp_line
			(start -0.67945 0.3048)
			(end -0.67945 -0.305054)
			(stroke
				(width 0.1)
				(type default)
			)
			(layer "F.Fab")
		)
		(fp_line
			(start -0.12065 0.3048)
			(end -0.67945 0.3048)
			(stroke
				(width 0.1)
				(type default)
			)
			(layer "F.Fab")
		)
		(fp_line
			(start 0.120396 0.3048)
			(end 0.120396 0.2794)
			(stroke
				(width 0.1)
				(type default)
			)
			(layer "F.Fab")
		)
		(fp_line
			(start 0.67945 0.3048)
			(end 0.120396 0.3048)
			(stroke
				(width 0.1)
				(type default)
			)
			(layer "F.Fab")
		)
		(fp_line
			(start -0.12065 0.2794)
			(end -0.12065 0.3048)
			(stroke
				(width 0.1)
				(type default)
			)
			(layer "F.Fab")
		)
		(fp_line
			(start 0.120396 0.2794)
			(end -0.12065 0.2794)
			(stroke
				(width 0.1)
				(type default)
			)
			(layer "F.Fab")
		)
		(fp_line
			(start -0.12065 -0.2794)
			(end 0.12065 -0.2794)
			(stroke
				(width 0.1)
				(type default)
			)
			(layer "F.Fab")
		)
		(fp_line
			(start 0.12065 -0.2794)
			(end 0.12065 -0.3048)
			(stroke
				(width 0.1)
				(type default)
			)
			(layer "F.Fab")
		)
		(fp_line
			(start 0.12065 -0.3048)
			(end 0.67945 -0.3048)
			(stroke
				(width 0.1)
				(type default)
			)
			(layer "F.Fab")
		)
		(fp_line
			(start 0.67945 -0.3048)
			(end 0.67945 0.3048)
			(stroke
				(width 0.1)
				(type default)
			)
			(layer "F.Fab")
		)
		(fp_line
			(start -0.67945 -0.305054)
			(end -0.12065 -0.305054)
			(stroke
				(width 0.1)
				(type default)
			)
			(layer "F.Fab")
		)
		(fp_line
			(start -0.12065 -0.305054)
			(end -0.12065 -0.2794)
			(stroke
				(width 0.1)
				(type default)
			)
			(layer "F.Fab")
		)
		(pad "1" smd circle
			(at -0.40005 0 270)
			(size 0 0)
			(layers "F.Cu" "F.Mask" "F.Paste")
			(net "PRSNT_SSD2_R1_N")
		)
		(pad "2" smd circle
			(at 0.40005 0 270)
			(size 0 0)
			(layers "F.Cu" "F.Mask" "F.Paste")
			(net "PRSNT_SSD2_R_N")
		)
	)
	(footprint ""
		(layer "F.Cu")
		(at 378.382022 -286.590232 180)
		(property "Reference" "C3583"
			(at 0 0 180)
			(layer "F.SilkS")
			(hide yes)
			(effects
				(font
					(size 1.27 1.27)
				)
			)
		)
		(property "Value" ""
			(at 0 0 180)
			(layer "F.Fab")
			(effects
				(font
					(size 1.27 1.27)
				)
			)
		)
		(duplicate_pad_numbers_are_jumpers no)
		(fp_line
			(start 1.2954 0.5842)
			(end -1.2954 0.5842)
			(stroke
				(width 0.1524)
				(type default)
			)
			(layer "F.SilkS")
		)
		(fp_line
			(start 1.2954 -0.5842)
			(end 1.2954 0.5842)
			(stroke
				(width 0.1524)
				(type default)
			)
			(layer "F.SilkS")
		)
		(fp_line
			(start -1.2954 0.5842)
			(end -1.2954 -0.5842)
			(stroke
				(width 0.1524)
				(type default)
			)
			(layer "F.SilkS")
		)
		(fp_line
			(start -1.2954 -0.5842)
			(end 1.2954 -0.5842)
			(stroke
				(width 0.1524)
				(type default)
			)
			(layer "F.SilkS")
		)
		(fp_line
			(start 1.1938 0.4064)
			(end 0.8636 0.4064)
			(stroke
				(width 0.1)
				(type default)
			)
			(layer "F.Fab")
		)
		(fp_line
			(start 1.1938 -0.4064)
			(end 1.1938 0.4064)
			(stroke
				(width 0.1)
				(type default)
			)
			(layer "F.Fab")
		)
		(fp_line
			(start 0.8636 0.4572)
			(end -0.8636 0.4572)
			(stroke
				(width 0.1)
				(type default)
			)
			(layer "F.Fab")
		)
		(fp_line
			(start 0.8636 0.4064)
			(end 0.8636 0.4572)
			(stroke
				(width 0.1)
				(type default)
			)
			(layer "F.Fab")
		)
		(fp_line
			(start 0.8636 -0.4064)
			(end 1.1938 -0.4064)
			(stroke
				(width 0.1)
				(type default)
			)
			(layer "F.Fab")
		)
		(fp_line
			(start 0.8636 -0.4572)
			(end 0.8636 -0.4064)
			(stroke
				(width 0.1)
				(type default)
			)
			(layer "F.Fab")
		)
		(fp_line
			(start -0.8636 0.4572)
			(end -0.8636 0.4064)
			(stroke
				(width 0.1)
				(type default)
			)
			(layer "F.Fab")
		)
		(fp_line
			(start -0.8636 0.4064)
			(end -1.1938 0.4064)
			(stroke
				(width 0.1)
				(type default)
			)
			(layer "F.Fab")
		)
		(fp_line
			(start -0.8636 -0.4064)
			(end -0.8636 -0.4572)
			(stroke
				(width 0.1)
				(type default)
			)
			(layer "F.Fab")
		)
		(fp_line
			(start -0.8636 -0.4572)
			(end 0.8636 -0.4572)
			(stroke
				(width 0.1)
				(type default)
			)
			(layer "F.Fab")
		)
		(fp_line
			(start -1.1938 0.4064)
			(end -1.1938 -0.4064)
			(stroke
				(width 0.1)
				(type default)
			)
			(layer "F.Fab")
		)
		(fp_line
			(start -1.1938 -0.4064)
			(end -0.8636 -0.4064)
			(stroke
				(width 0.1)
				(type default)
			)
			(layer "F.Fab")
		)
		(pad "1" smd rect
			(at -0.7366 0 90)
			(size 0.7112 0.8128)
			(layers "F.Cu" "F.Mask" "F.Paste")
			(net "PCEPLL6_VDDA18_PEX3_R")
		)
		(pad "2" smd rect
			(at 0.7366 0 90)
			(size 0.7112 0.8128)
			(layers "F.Cu" "F.Mask" "F.Paste")
			(net "GND")
		)
	)
	(footprint ""
		(layer "F.Cu")
		(at 251.96546 -195.573396 90)
		(property "Reference" "R875"
			(at 0 0 90)
			(layer "F.SilkS")
			(hide yes)
			(effects
				(font
					(size 1.27 1.27)
				)
			)
		)
		(property "Value" ""
			(at 0 0 90)
			(layer "F.Fab")
			(effects
				(font
					(size 1.27 1.27)
				)
			)
		)
		(duplicate_pad_numbers_are_jumpers no)
		(fp_line
			(start 0.7874 -0.4064)
			(end 0.7874 0.4064)
			(stroke
				(width 0.1524)
				(type default)
			)
			(layer "F.SilkS")
		)
		(fp_line
			(start -0.7874 -0.4064)
			(end 0.7874 -0.4064)
			(stroke
				(width 0.1524)
				(type default)
			)
			(layer "F.SilkS")
		)
		(fp_line
			(start 0.7874 0.4064)
			(end -0.7874 0.4064)
			(stroke
				(width 0.1524)
				(type default)
			)
			(layer "F.SilkS")
		)
		(fp_line
			(start -0.7874 0.4064)
			(end -0.7874 -0.4064)
			(stroke
				(width 0.1524)
				(type default)
			)
			(layer "F.SilkS")
		)
		(fp_line
			(start -0.12065 -0.305054)
			(end -0.12065 -0.2794)
			(stroke
				(width 0.1)
				(type default)
			)
			(layer "F.Fab")
		)
		(fp_line
			(start -0.67945 -0.305054)
			(end -0.12065 -0.305054)
			(stroke
				(width 0.1)
				(type default)
			)
			(layer "F.Fab")
		)
		(fp_line
			(start 0.67945 -0.3048)
			(end 0.67945 0.3048)
			(stroke
				(width 0.1)
				(type default)
			)
			(layer "F.Fab")
		)
		(fp_line
			(start 0.12065 -0.3048)
			(end 0.67945 -0.3048)
			(stroke
				(width 0.1)
				(type default)
			)
			(layer "F.Fab")
		)
		(fp_line
			(start 0.12065 -0.2794)
			(end 0.12065 -0.3048)
			(stroke
				(width 0.1)
				(type default)
			)
			(layer "F.Fab")
		)
		(fp_line
			(start -0.12065 -0.2794)
			(end 0.12065 -0.2794)
			(stroke
				(width 0.1)
				(type default)
			)
			(layer "F.Fab")
		)
		(fp_line
			(start 0.120396 0.2794)
			(end -0.12065 0.2794)
			(stroke
				(width 0.1)
				(type default)
			)
			(layer "F.Fab")
		)
		(fp_line
			(start -0.12065 0.2794)
			(end -0.12065 0.3048)
			(stroke
				(width 0.1)
				(type default)
			)
			(layer "F.Fab")
		)
		(fp_line
			(start 0.67945 0.3048)
			(end 0.120396 0.3048)
			(stroke
				(width 0.1)
				(type default)
			)
			(layer "F.Fab")
		)
		(fp_line
			(start 0.120396 0.3048)
			(end 0.120396 0.2794)
			(stroke
				(width 0.1)
				(type default)
			)
			(layer "F.Fab")
		)
		(fp_line
			(start -0.12065 0.3048)
			(end -0.67945 0.3048)
			(stroke
				(width 0.1)
				(type default)
			)
			(layer "F.Fab")
		)
		(fp_line
			(start -0.67945 0.3048)
			(end -0.67945 -0.305054)
			(stroke
				(width 0.1)
				(type default)
			)
			(layer "F.Fab")
		)
		(pad "1" smd circle
			(at -0.40005 0 90)
			(size 0 0)
			(layers "F.Cu" "F.Mask" "F.Paste")
			(net "JTAG_FPGA_TCK")
		)
		(pad "2" smd circle
			(at 0.40005 0 90)
			(size 0 0)
			(layers "F.Cu" "F.Mask" "F.Paste")
			(net "GND")
		)
	)
	(footprint ""
		(layer "F.Cu")
		(at 338.074 -186.055)
		(property "Reference" "R4748"
			(at 0 0 0)
			(layer "F.SilkS")
			(hide yes)
			(effects
				(font
					(size 1.27 1.27)
				)
			)
		)
		(property "Value" ""
			(at 0 0 0)
			(layer "F.Fab")
			(effects
				(font
					(size 1.27 1.27)
				)
			)
		)
		(duplicate_pad_numbers_are_jumpers no)
		(fp_line
			(start -0.7874 -0.4064)
			(end 0.7874 -0.4064)
			(stroke
				(width 0.1524)
				(type default)
			)
			(layer "F.SilkS")
		)
		(fp_line
			(start -0.7874 0.4064)
			(end -0.7874 -0.4064)
			(stroke
				(width 0.1524)
				(type default)
			)
			(layer "F.SilkS")
		)
		(fp_line
			(start 0.7874 -0.4064)
			(end 0.7874 0.4064)
			(stroke
				(width 0.1524)
				(type default)
			)
			(layer "F.SilkS")
		)
		(fp_line
			(start 0.7874 0.4064)
			(end -0.7874 0.4064)
			(stroke
				(width 0.1524)
				(type default)
			)
			(layer "F.SilkS")
		)
		(fp_line
			(start -0.67945 -0.305054)
			(end -0.12065 -0.305054)
			(stroke
				(width 0.1)
				(type default)
			)
			(layer "F.Fab")
		)
		(fp_line
			(start -0.67945 0.3048)
			(end -0.67945 -0.305054)
			(stroke
				(width 0.1)
				(type default)
			)
			(layer "F.Fab")
		)
		(fp_line
			(start -0.12065 -0.305054)
			(end -0.12065 -0.2794)
			(stroke
				(width 0.1)
				(type default)
			)
			(layer "F.Fab")
		)
		(fp_line
			(start -0.12065 -0.2794)
			(end 0.12065 -0.2794)
			(stroke
				(width 0.1)
				(type default)
			)
			(layer "F.Fab")
		)
		(fp_line
			(start -0.12065 0.2794)
			(end -0.12065 0.3048)
			(stroke
				(width 0.1)
				(type default)
			)
			(layer "F.Fab")
		)
		(fp_line
			(start -0.12065 0.3048)
			(end -0.67945 0.3048)
			(stroke
				(width 0.1)
				(type default)
			)
			(layer "F.Fab")
		)
		(fp_line
			(start 0.120396 0.2794)
			(end -0.12065 0.2794)
			(stroke
				(width 0.1)
				(type default)
			)
			(layer "F.Fab")
		)
		(fp_line
			(start 0.120396 0.3048)
			(end 0.120396 0.2794)
			(stroke
				(width 0.1)
				(type default)
			)
			(layer "F.Fab")
		)
		(fp_line
			(start 0.12065 -0.3048)
			(end 0.67945 -0.3048)
			(stroke
				(width 0.1)
				(type default)
			)
			(layer "F.Fab")
		)
		(fp_line
			(start 0.12065 -0.2794)
			(end 0.12065 -0.3048)
			(stroke
				(width 0.1)
				(type default)
			)
			(layer "F.Fab")
		)
		(fp_line
			(start 0.67945 -0.3048)
			(end 0.67945 0.3048)
			(stroke
				(width 0.1)
				(type default)
			)
			(layer "F.Fab")
		)
		(fp_line
			(start 0.67945 0.3048)
			(end 0.120396 0.3048)
			(stroke
				(width 0.1)
				(type default)
			)
			(layer "F.Fab")
		)
		(pad "1" smd circle
			(at -0.40005 0)
			(size 0 0)
			(layers "F.Cu" "F.Mask" "F.Paste")
			(net "PEX2_PCA9555_0_INT_N")
		)
		(pad "2" smd circle
			(at 0.40005 0)
			(size 0 0)
			(layers "F.Cu" "F.Mask" "F.Paste")
			(net "P1V8_PEX")
		)
	)
	(footprint ""
		(layer "F.Cu")
		(at 136.445244 -99.243642 180)
		(property "Reference" "R1573"
			(at 0 0 180)
			(layer "F.SilkS")
			(hide yes)
			(effects
				(font
					(size 1.27 1.27)
				)
			)
		)
		(property "Value" ""
			(at 0 0 180)
			(layer "F.Fab")
			(effects
				(font
					(size 1.27 1.27)
				)
			)
		)
		(duplicate_pad_numbers_are_jumpers no)
		(fp_line
			(start 0.7874 0.4064)
			(end -0.7874 0.4064)
			(stroke
				(width 0.1524)
				(type default)
			)
			(layer "F.SilkS")
		)
		(fp_line
			(start 0.7874 -0.4064)
			(end 0.7874 0.4064)
			(stroke
				(width 0.1524)
				(type default)
			)
			(layer "F.SilkS")
		)
		(fp_line
			(start -0.7874 0.4064)
			(end -0.7874 -0.4064)
			(stroke
				(width 0.1524)
				(type default)
			)
			(layer "F.SilkS")
		)
		(fp_line
			(start -0.7874 -0.4064)
			(end 0.7874 -0.4064)
			(stroke
				(width 0.1524)
				(type default)
			)
			(layer "F.SilkS")
		)
		(fp_line
			(start 0.67945 0.3048)
			(end 0.120396 0.3048)
			(stroke
				(width 0.1)
				(type default)
			)
			(layer "F.Fab")
		)
		(fp_line
			(start 0.67945 -0.3048)
			(end 0.67945 0.3048)
			(stroke
				(width 0.1)
				(type default)
			)
			(layer "F.Fab")
		)
		(fp_line
			(start 0.12065 -0.2794)
			(end 0.12065 -0.3048)
			(stroke
				(width 0.1)
				(type default)
			)
			(layer "F.Fab")
		)
		(fp_line
			(start 0.12065 -0.3048)
			(end 0.67945 -0.3048)
			(stroke
				(width 0.1)
				(type default)
			)
			(layer "F.Fab")
		)
		(fp_line
			(start 0.120396 0.3048)
			(end 0.120396 0.2794)
			(stroke
				(width 0.1)
				(type default)
			)
			(layer "F.Fab")
		)
		(fp_line
			(start 0.120396 0.2794)
			(end -0.12065 0.2794)
			(stroke
				(width 0.1)
				(type default)
			)
			(layer "F.Fab")
		)
		(fp_line
			(start -0.12065 0.3048)
			(end -0.67945 0.3048)
			(stroke
				(width 0.1)
				(type default)
			)
			(layer "F.Fab")
		)
		(fp_line
			(start -0.12065 0.2794)
			(end -0.12065 0.3048)
			(stroke
				(width 0.1)
				(type default)
			)
			(layer "F.Fab")
		)
		(fp_line
			(start -0.12065 -0.2794)
			(end 0.12065 -0.2794)
			(stroke
				(width 0.1)
				(type default)
			)
			(layer "F.Fab")
		)
		(fp_line
			(start -0.12065 -0.305054)
			(end -0.12065 -0.2794)
			(stroke
				(width 0.1)
				(type default)
			)
			(layer "F.Fab")
		)
		(fp_line
			(start -0.67945 0.3048)
			(end -0.67945 -0.305054)
			(stroke
				(width 0.1)
				(type default)
			)
			(layer "F.Fab")
		)
		(fp_line
			(start -0.67945 -0.305054)
			(end -0.12065 -0.305054)
			(stroke
				(width 0.1)
				(type default)
			)
			(layer "F.Fab")
		)
		(pad "1" smd circle
			(at -0.40005 0 180)
			(size 0 0)
			(layers "F.Cu" "F.Mask" "F.Paste")
			(net "SMB_BIC_I2C9_SSD_MUX_R_SDA")
		)
		(pad "2" smd circle
			(at 0.40005 0 180)
			(size 0 0)
			(layers "F.Cu" "F.Mask" "F.Paste")
			(net "SMB_BIC_I2C9_SSD_MUX0_SDA")
		)
	)
	(footprint ""
		(layer "F.Cu")
		(at 131.25958 -152.71115 -90)
		(property "Reference" "R709"
			(at 0 0 270)
			(layer "F.SilkS")
			(hide yes)
			(effects
				(font
					(size 1.27 1.27)
				)
			)
		)
		(property "Value" ""
			(at 0 0 270)
			(layer "F.Fab")
			(effects
				(font
					(size 1.27 1.27)
				)
			)
		)
		(duplicate_pad_numbers_are_jumpers no)
		(fp_line
			(start -0.7874 0.4064)
			(end -0.7874 -0.4064)
			(stroke
				(width 0.1524)
				(type default)
			)
			(layer "F.SilkS")
		)
		(fp_line
			(start 0.7874 0.4064)
			(end -0.7874 0.4064)
			(stroke
				(width 0.1524)
				(type default)
			)
			(layer "F.SilkS")
		)
		(fp_line
			(start -0.7874 -0.4064)
			(end 0.7874 -0.4064)
			(stroke
				(width 0.1524)
				(type default)
			)
			(layer "F.SilkS")
		)
		(fp_line
			(start 0.7874 -0.4064)
			(end 0.7874 0.4064)
			(stroke
				(width 0.1524)
				(type default)
			)
			(layer "F.SilkS")
		)
		(fp_line
			(start -0.67945 0.3048)
			(end -0.67945 -0.305054)
			(stroke
				(width 0.1)
				(type default)
			)
			(layer "F.Fab")
		)
		(fp_line
			(start -0.12065 0.3048)
			(end -0.67945 0.3048)
			(stroke
				(width 0.1)
				(type default)
			)
			(layer "F.Fab")
		)
		(fp_line
			(start 0.120396 0.3048)
			(end 0.120396 0.2794)
			(stroke
				(width 0.1)
				(type default)
			)
			(layer "F.Fab")
		)
		(fp_line
			(start 0.67945 0.3048)
			(end 0.120396 0.3048)
			(stroke
				(width 0.1)
				(type default)
			)
			(layer "F.Fab")
		)
		(fp_line
			(start -0.12065 0.2794)
			(end -0.12065 0.3048)
			(stroke
				(width 0.1)
				(type default)
			)
			(layer "F.Fab")
		)
		(fp_line
			(start 0.120396 0.2794)
			(end -0.12065 0.2794)
			(stroke
				(width 0.1)
				(type default)
			)
			(layer "F.Fab")
		)
		(fp_line
			(start -0.12065 -0.2794)
			(end 0.12065 -0.2794)
			(stroke
				(width 0.1)
				(type default)
			)
			(layer "F.Fab")
		)
		(fp_line
			(start 0.12065 -0.2794)
			(end 0.12065 -0.3048)
			(stroke
				(width 0.1)
				(type default)
			)
			(layer "F.Fab")
		)
		(fp_line
			(start 0.12065 -0.3048)
			(end 0.67945 -0.3048)
			(stroke
				(width 0.1)
				(type default)
			)
			(layer "F.Fab")
		)
		(fp_line
			(start 0.67945 -0.3048)
			(end 0.67945 0.3048)
			(stroke
				(width 0.1)
				(type default)
			)
			(layer "F.Fab")
		)
		(fp_line
			(start -0.67945 -0.305054)
			(end -0.12065 -0.305054)
			(stroke
				(width 0.1)
				(type default)
			)
			(layer "F.Fab")
		)
		(fp_line
			(start -0.12065 -0.305054)
			(end -0.12065 -0.2794)
			(stroke
				(width 0.1)
				(type default)
			)
			(layer "F.Fab")
		)
		(pad "1" smd circle
			(at -0.40005 0 270)
			(size 0 0)
			(layers "F.Cu" "F.Mask" "F.Paste")
			(net "SMB_BIC_I2C6_MUX_NIC_ADC_R_SCL")
		)
		(pad "2" smd circle
			(at 0.40005 0 270)
			(size 0 0)
			(layers "F.Cu" "F.Mask" "F.Paste")
			(net "SMB_NIC2_ADC_SCL")
		)
	)
)
